(kicad_pcb
	(version 20260206)
	(generator "pcbnew")
	(generator_version "10.0")
	(general
		(thickness 1.6)
		(legacy_teardrops no)
	)
	(paper "A4")
	(title_block
		(title "ptb — 12523-1.1018WZS1506.brd")
		(comment 1 "Open Vault / Knox (Wiwynn) / footprints 31-33 of 61")
	)
	(layers
		(0 "F.Cu" signal "TOP")
		(4 "In1.Cu" signal "L2GND")
		(6 "In2.Cu" signal "L3VCC")
		(2 "B.Cu" signal "BOTTOM")
		(9 "F.Adhes" user "F.Adhesive")
		(11 "B.Adhes" user "B.Adhesive")
		(13 "F.Paste" user "Package Geometry/Pastemask Top")
		(15 "B.Paste" user "Package Geometry/Pastemask Bottom")
		(5 "F.SilkS" user "Ref Des/Silkscreen Top")
		(7 "B.SilkS" user "Ref Des/Silkscreen Bottom")
		(1 "F.Mask" user "Board Geometry/Soldermask Top")
		(3 "B.Mask" user "Board Geometry/Soldermask Bottom")
		(17 "Dwgs.User" user "User.Drawings")
		(19 "Cmts.User" user "User.Comments")
		(21 "Eco1.User" user "User.Eco1")
		(23 "Eco2.User" user "User.Eco2")
		(25 "Edge.Cuts" user "Board Geometry/Outline")
		(27 "Margin" user)
		(31 "F.CrtYd" user "Package Geometry/Place Bound Top")
		(29 "B.CrtYd" user "Package Geometry/Place Bound Bottom")
		(35 "F.Fab" user "Ref Des/Assembly Top")
		(33 "B.Fab" user "Ref Des/Assembly Bottom")
	)
	(footprint ""
		(layer "F.Cu")
		(at 135.086344 -85.065108 -90)
		(property "Reference" "R366"
			(at 0 0 270)
			(layer "F.SilkS")
			(hide yes)
			(effects
				(font
					(size 1.27 1.27)
				)
			)
		)
		(property "Value" "0R2J-2-GP"
			(at 0.064008 -3.993896 270)
			(unlocked yes)
			(layer "F.Fab")
			(hide yes)
			(effects
				(font
					(size 1.016 1.016)
					(thickness 0.1524)
				)
			)
		)
		(property "Device Type" "R402H16"
			(at 0.064008 -5.517896 270)
			(unlocked yes)
			(layer "F.Fab")
			(hide yes)
			(effects
				(font
					(size 1.016 1.016)
					(thickness 0.1524)
				)
			)
		)
		(duplicate_pad_numbers_are_jumpers no)
		(fp_line
			(start -0.508 -0.9398)
			(end -0.508 0.9398)
			(stroke
				(width 0.1524)
				(type default)
			)
			(layer "F.SilkS")
		)
		(fp_line
			(start 0.508 -0.9398)
			(end -0.508 -0.9398)
			(stroke
				(width 0.1524)
				(type default)
			)
			(layer "F.SilkS")
		)
		(fp_rect
			(start -0.508 0.9398)
			(end 0.508 -0.9398)
			(stroke
				(width 0)
				(type default)
			)
			(fill no)
			(layer "F.CrtYd")
		)
		(fp_rect
			(start -0.508 0.9398)
			(end 0.508 -0.9398)
			(stroke
				(width 0)
				(type default)
			)
			(fill no)
			(layer "F.Fab")
		)
		(pad "1" smd custom
			(at 0 -0.4445 270)
			(size 0.1397 0.1397)
			(layers "F.Cu" "F.Mask" "F.Paste")
			(net "IR_SWITCH_E")
			(options
				(clearance outline)
				(anchor circle)
			)
			(primitives
				(gr_poly
					(pts
						(arc
							(start -0.1778 -0.2794)
							(mid -0.249642 -0.249642)
							(end -0.2794 -0.1778)
						)
						(arc
							(start -0.2794 0.1778)
							(mid -0.249642 0.249642)
							(end -0.1778 0.2794)
						)
						(arc
							(start 0.1778 0.2794)
							(mid 0.249642 0.249642)
							(end 0.2794 0.1778)
						)
						(arc
							(start 0.2794 -0.1778)
							(mid 0.249642 -0.249642)
							(end 0.1778 -0.2794)
						)
					)
					(width 0)
					(fill yes)
				)
			)
		)
		(pad "2" smd custom
			(at 0 0.4445 270)
			(size 0.1397 0.1397)
			(layers "F.Cu" "F.Mask" "F.Paste")
			(net "TRAY PRESENT_OUT_NET")
			(options
				(clearance outline)
				(anchor circle)
			)
			(primitives
				(gr_poly
					(pts
						(arc
							(start -0.1778 -0.2794)
							(mid -0.249642 -0.249642)
							(end -0.2794 -0.1778)
						)
						(arc
							(start -0.2794 0.1778)
							(mid -0.249642 0.249642)
							(end -0.1778 0.2794)
						)
						(arc
							(start 0.1778 0.2794)
							(mid 0.249642 0.249642)
							(end 0.2794 0.1778)
						)
						(arc
							(start 0.2794 -0.1778)
							(mid 0.249642 -0.249642)
							(end 0.1778 -0.2794)
						)
					)
					(width 0)
					(fill yes)
				)
			)
		)
	)
	(footprint ""
		(layer "F.Cu")
		(at 113.919 -47.371 180)
		(property "Reference" "C362"
			(at 0 0 180)
			(layer "F.SilkS")
			(hide yes)
			(effects
				(font
					(size 1.27 1.27)
				)
			)
		)
		(property "Value" "SC47U16V0MX-GP"
			(at -0.00254 -4.78536 180)
			(unlocked yes)
			(layer "F.Fab")
			(hide yes)
			(effects
				(font
					(size 1.016 1.016)
					(thickness 0.1524)
				)
			)
		)
		(property "Device Type" "C1210H107"
			(at -0.00254 -6.38048 180)
			(unlocked yes)
			(layer "F.Fab")
			(hide yes)
			(effects
				(font
					(size 1.016 1.016)
					(thickness 0.1524)
				)
			)
		)
		(duplicate_pad_numbers_are_jumpers no)
		(fp_line
			(start 1.5748 2.3368)
			(end 1.5748 0.762)
			(stroke
				(width 0.1524)
				(type default)
			)
			(layer "F.SilkS")
		)
		(fp_line
			(start 1.5748 -0.762)
			(end 1.5748 -2.3368)
			(stroke
				(width 0.1524)
				(type default)
			)
			(layer "F.SilkS")
		)
		(fp_line
			(start 1.5748 -2.3368)
			(end -1.5748 -2.3368)
			(stroke
				(width 0.1524)
				(type default)
			)
			(layer "F.SilkS")
		)
		(fp_line
			(start -1.5748 2.3368)
			(end 1.5748 2.3368)
			(stroke
				(width 0.1524)
				(type default)
			)
			(layer "F.SilkS")
		)
		(fp_line
			(start -1.5748 0.762)
			(end -1.5748 2.3368)
			(stroke
				(width 0.1524)
				(type default)
			)
			(layer "F.SilkS")
		)
		(fp_line
			(start -1.5748 -2.3368)
			(end -1.5748 -0.762)
			(stroke
				(width 0.1524)
				(type default)
			)
			(layer "F.SilkS")
		)
		(fp_rect
			(start -1.651 2.413)
			(end 1.651 -2.413)
			(stroke
				(width 0)
				(type default)
			)
			(fill no)
			(layer "F.CrtYd")
		)
		(fp_poly
			(pts
				(xy 1.651 2.413) (xy 1.651 -2.413) (xy -1.651 -2.413) (xy -1.651 2.413)
			)
			(stroke
				(width 0)
				(type default)
			)
			(fill no)
			(layer "F.Fab")
		)
		(pad "1" smd rect
			(at 0 -1.4732 180)
			(size 2.794 1.397)
			(layers "F.Cu" "F.Mask" "F.Paste")
			(net "P12V")
		)
		(pad "2" smd rect
			(at 0 1.4732 180)
			(size 2.794 1.397)
			(layers "F.Cu" "F.Mask" "F.Paste")
			(net "GND")
		)
	)
	(footprint ""
		(layer "F.Cu")
		(at 135.111744 -82.906108 90)
		(property "Reference" "R374"
			(at 0 0 90)
			(layer "F.SilkS")
			(hide yes)
			(effects
				(font
					(size 1.27 1.27)
				)
			)
		)
		(property "Value" "470KR2F-GP"
			(at 0.064008 -3.993896 90)
			(unlocked yes)
			(layer "F.Fab")
			(hide yes)
			(effects
				(font
					(size 1.016 1.016)
					(thickness 0.1524)
				)
			)
		)
		(property "Device Type" "R402H16"
			(at 0.064008 -5.517896 90)
			(unlocked yes)
			(layer "F.Fab")
			(hide yes)
			(effects
				(font
					(size 1.016 1.016)
					(thickness 0.1524)
				)
			)
		)
		(duplicate_pad_numbers_are_jumpers no)
		(fp_line
			(start 0.508 -0.9398)
			(end -0.508 -0.9398)
			(stroke
				(width 0.1524)
				(type default)
			)
			(layer "F.SilkS")
		)
		(fp_line
			(start -0.508 -0.9398)
			(end -0.508 0.9398)
			(stroke
				(width 0.1524)
				(type default)
			)
			(layer "F.SilkS")
		)
		(fp_rect
			(start -0.508 0.9398)
			(end 0.508 -0.9398)
			(stroke
				(width 0)
				(type default)
			)
			(fill no)
			(layer "F.CrtYd")
		)
		(fp_rect
			(start -0.508 0.9398)
			(end 0.508 -0.9398)
			(stroke
				(width 0)
				(type default)
			)
			(fill no)
			(layer "F.Fab")
		)
		(pad "1" smd custom
			(at 0 -0.4445 90)
			(size 0.1397 0.1397)
			(layers "F.Cu" "F.Mask" "F.Paste")
			(net "TRAY PRESENT_OUT_NET")
			(options
				(clearance outline)
				(anchor circle)
			)
			(primitives
				(gr_poly
					(pts
						(arc
							(start -0.1778 -0.2794)
							(mid -0.249642 -0.249642)
							(end -0.2794 -0.1778)
						)
						(arc
							(start -0.2794 0.1778)
							(mid -0.249642 0.249642)
							(end -0.1778 0.2794)
						)
						(arc
							(start 0.1778 0.2794)
							(mid 0.249642 0.249642)
							(end 0.2794 0.1778)
						)
						(arc
							(start 0.2794 -0.1778)
							(mid 0.249642 -0.249642)
							(end 0.1778 -0.2794)
						)
					)
					(width 0)
					(fill yes)
				)
			)
		)
		(pad "2" smd custom
			(at 0 0.4445 90)
			(size 0.1397 0.1397)
			(layers "F.Cu" "F.Mask" "F.Paste")
			(net "GND")
			(options
				(clearance outline)
				(anchor circle)
			)
			(primitives
				(gr_poly
					(pts
						(arc
							(start -0.1778 -0.2794)
							(mid -0.249642 -0.249642)
							(end -0.2794 -0.1778)
						)
						(arc
							(start -0.2794 0.1778)
							(mid -0.249642 0.249642)
							(end -0.1778 0.2794)
						)
						(arc
							(start 0.1778 0.2794)
							(mid 0.249642 0.249642)
							(end 0.2794 0.1778)
						)
						(arc
							(start 0.2794 -0.1778)
							(mid 0.249642 -0.249642)
							(end 0.1778 -0.2794)
						)
					)
					(width 0)
					(fill yes)
				)
			)
		)
	)
)
